(kicad_pcb
	(version 20260206)
	(generator "pcbnew")
	(generator_version "10.0")
	(general
		(thickness 1.6)
		(legacy_teardrops no)
	)
	(paper "A4")
	(title_block
		(title "peb — Lightning_PEB_BRD.brd")
		(comment 1 "Lightning (Wiwynn / Facebook NVMe JBOF) / footprints 373-379 of 2563")
	)
	(layers
		(0 "F.Cu" signal "TOP")
		(4 "In1.Cu" signal "L2GND")
		(6 "In2.Cu" signal "L3")
		(8 "In3.Cu" signal "L4VCC")
		(10 "In4.Cu" signal "L5VCC")
		(12 "In5.Cu" signal "L6")
		(14 "In6.Cu" signal "L7GND")
		(2 "B.Cu" signal "BOTTOM")
		(9 "F.Adhes" user "F.Adhesive")
		(11 "B.Adhes" user "B.Adhesive")
		(13 "F.Paste" user "Package Geometry/Pastemask Top")
		(15 "B.Paste" user "Package Geometry/Pastemask Bottom")
		(5 "F.SilkS" user "Ref Des/Silkscreen Top")
		(7 "B.SilkS" user "Ref Des/Silkscreen Bottom")
		(1 "F.Mask" user "Board Geometry/Soldermask Top")
		(3 "B.Mask" user "Board Geometry/Soldermask Bottom")
		(17 "Dwgs.User" user "User.Drawings")
		(19 "Cmts.User" user "User.Comments")
		(21 "Eco1.User" user "User.Eco1")
		(23 "Eco2.User" user "User.Eco2")
		(25 "Edge.Cuts" user "Board Geometry/Outline")
		(27 "Margin" user)
		(31 "F.CrtYd" user "Package Geometry/Place Bound Top")
		(29 "B.CrtYd" user "Package Geometry/Place Bound Bottom")
		(35 "F.Fab" user "Ref Des/Assembly Top")
		(33 "B.Fab" user "Ref Des/Assembly Bottom")
	)
	(footprint ""
		(layer "F.Cu")
		(at 334.804512 -172.432218)
		(property "Reference" "R7951"
			(at 0 0 0)
			(layer "F.SilkS")
			(hide yes)
			(effects
				(font
					(size 1.27 1.27)
				)
			)
		)
		(property "Value" "0R2J-2-GP"
			(at 0.064008 -3.993896 0)
			(unlocked yes)
			(layer "F.Fab")
			(hide yes)
			(effects
				(font
					(size 1.016 1.016)
					(thickness 0.1524)
				)
			)
		)
		(property "Device Type" "R402H16"
			(at 0.064008 -5.517896 0)
			(unlocked yes)
			(layer "F.Fab")
			(hide yes)
			(effects
				(font
					(size 1.016 1.016)
					(thickness 0.1524)
				)
			)
		)
		(duplicate_pad_numbers_are_jumpers no)
		(fp_line
			(start -0.508 -0.9398)
			(end -0.508 0.9398)
			(stroke
				(width 0.1524)
				(type default)
			)
			(layer "F.SilkS")
		)
		(fp_line
			(start 0.508 -0.9398)
			(end -0.508 -0.9398)
			(stroke
				(width 0.1524)
				(type default)
			)
			(layer "F.SilkS")
		)
		(fp_rect
			(start -0.508 0.9398)
			(end 0.508 -0.9398)
			(stroke
				(width 0)
				(type default)
			)
			(fill no)
			(layer "F.CrtYd")
		)
		(fp_rect
			(start -0.508 0.9398)
			(end 0.508 -0.9398)
			(stroke
				(width 0)
				(type default)
			)
			(fill no)
			(layer "F.Fab")
		)
		(pad "1" smd custom
			(at 0 -0.4445)
			(size 0.1397 0.1397)
			(layers "F.Cu" "F.Mask" "F.Paste")
			(net "SSD_PWREN4")
			(options
				(clearance outline)
				(anchor circle)
			)
			(primitives
				(gr_poly
					(pts
						(arc
							(start -0.1778 -0.2794)
							(mid -0.249642 -0.249642)
							(end -0.2794 -0.1778)
						)
						(arc
							(start -0.2794 0.1778)
							(mid -0.249642 0.249642)
							(end -0.1778 0.2794)
						)
						(arc
							(start 0.1778 0.2794)
							(mid 0.249642 0.249642)
							(end 0.2794 0.1778)
						)
						(arc
							(start 0.2794 -0.1778)
							(mid 0.249642 -0.249642)
							(end 0.1778 -0.2794)
						)
					)
					(width 0)
					(fill yes)
				)
			)
		)
		(pad "2" smd custom
			(at 0 0.4445)
			(size 0.1397 0.1397)
			(layers "F.Cu" "F.Mask" "F.Paste")
			(net "SSD_PWREN4_R")
			(options
				(clearance outline)
				(anchor circle)
			)
			(primitives
				(gr_poly
					(pts
						(arc
							(start -0.1778 -0.2794)
							(mid -0.249642 -0.249642)
							(end -0.2794 -0.1778)
						)
						(arc
							(start -0.2794 0.1778)
							(mid -0.249642 0.249642)
							(end -0.1778 0.2794)
						)
						(arc
							(start 0.1778 0.2794)
							(mid 0.249642 0.249642)
							(end 0.2794 0.1778)
						)
						(arc
							(start 0.2794 -0.1778)
							(mid 0.249642 -0.249642)
							(end 0.1778 -0.2794)
						)
					)
					(width 0)
					(fill yes)
				)
			)
		)
	)
	(footprint ""
		(layer "F.Cu")
		(at 223.774 -0.635 -90)
		(property "Reference" "U27"
			(at 0 0 270)
			(layer "F.SilkS")
			(hide yes)
			(effects
				(font
					(size 1.27 1.27)
				)
			)
		)
		(property "Value" "TS5A23157DGSR-GP"
			(at 0 -11.1252 270)
			(unlocked yes)
			(layer "F.Fab")
			(hide yes)
			(effects
				(font
					(size 1.016 1.016)
					(thickness 0.1524)
				)
			)
		)
		(property "Device Type" "MSOP10H44"
			(at 0 -12.6492 270)
			(unlocked yes)
			(layer "F.Fab")
			(hide yes)
			(effects
				(font
					(size 1.016 1.016)
					(thickness 0.1524)
				)
			)
		)
		(duplicate_pad_numbers_are_jumpers no)
		(fp_line
			(start -2.0066 1.016)
			(end -2.0066 -1.016)
			(stroke
				(width 0.1524)
				(type default)
			)
			(layer "F.SilkS")
		)
		(fp_line
			(start -1.8288 1.016)
			(end -1.8288 3.048)
			(stroke
				(width 0.508)
				(type default)
			)
			(layer "F.SilkS")
		)
		(fp_line
			(start 1.143 1.016)
			(end -2.0066 1.016)
			(stroke
				(width 0.1524)
				(type default)
			)
			(layer "F.SilkS")
		)
		(fp_line
			(start -1.5748 0)
			(end -1.9558 0.381)
			(stroke
				(width 0.1524)
				(type default)
			)
			(layer "F.SilkS")
		)
		(fp_line
			(start -1.5748 0)
			(end -1.9558 -0.381)
			(stroke
				(width 0.1524)
				(type default)
			)
			(layer "F.SilkS")
		)
		(fp_line
			(start -2.0066 -1.016)
			(end 1.143 -1.016)
			(stroke
				(width 0.1524)
				(type default)
			)
			(layer "F.SilkS")
		)
		(fp_line
			(start 1.143 -1.016)
			(end 1.143 1.016)
			(stroke
				(width 0.1524)
				(type default)
			)
			(layer "F.SilkS")
		)
		(fp_poly
			(pts
				(xy -2.0828 3.3401) (xy 2.0828 3.3401) (xy 2.0828 -3.3401) (xy -2.0828 -3.3401)
			)
			(stroke
				(width 0)
				(type default)
			)
			(fill no)
			(layer "F.CrtYd")
		)
		(fp_poly
			(pts
				(xy -2.0828 3.3401) (xy 2.0828 3.3401) (xy 2.0828 -3.3401) (xy -2.0828 -3.3401)
			)
			(stroke
				(width 0)
				(type default)
			)
			(fill no)
			(layer "F.Fab")
		)
		(pad "1" smd rect
			(at -0.99949 2.0701 270)
			(size 0.3048 1.524)
			(layers "F.Cu" "F.Mask" "F.Paste")
			(net "UART_SWITCH_R")
		)
		(pad "2" smd rect
			(at -0.50038 2.0701 270)
			(size 0.3048 1.524)
			(layers "F.Cu" "F.Mask" "F.Paste")
			(net "EXP_UART_TX_R")
		)
		(pad "3" smd rect
			(at 0 2.0701 270)
			(size 0.3048 1.524)
			(layers "F.Cu" "F.Mask" "F.Paste")
			(net "GND")
		)
		(pad "4" smd rect
			(at 0.50038 2.0701 270)
			(size 0.3048 1.524)
			(layers "F.Cu" "F.Mask" "F.Paste")
			(net "EXP_UART_RX_R")
		)
		(pad "5" smd rect
			(at 0.99949 2.0701 270)
			(size 0.3048 1.524)
			(layers "F.Cu" "F.Mask" "F.Paste")
			(net "UART_SWITCH_R")
		)
		(pad "6" smd rect
			(at 0.99949 -2.0701 270)
			(size 0.3048 1.524)
			(layers "F.Cu" "F.Mask" "F.Paste")
			(net "DEBUG_CARD_RX")
		)
		(pad "7" smd rect
			(at 0.50038 -2.0701 270)
			(size 0.3048 1.524)
			(layers "F.Cu" "F.Mask" "F.Paste")
			(net "BMC_RXD5")
		)
		(pad "8" smd rect
			(at 0 -2.0701 270)
			(size 0.3048 1.524)
			(layers "F.Cu" "F.Mask" "F.Paste")
			(net "P3V3_STBY")
		)
		(pad "9" smd rect
			(at -0.50038 -2.0701 270)
			(size 0.3048 1.524)
			(layers "F.Cu" "F.Mask" "F.Paste")
			(net "BMC_TXD5")
		)
		(pad "10" smd rect
			(at -0.99949 -2.0701 270)
			(size 0.3048 1.524)
			(layers "F.Cu" "F.Mask" "F.Paste")
			(net "DEBUG_CARD_TX")
		)
	)
	(footprint ""
		(layer "F.Cu")
		(at 40.576754 -146.465544)
		(property "Reference" "C185"
			(at 0 0 0)
			(layer "F.SilkS")
			(hide yes)
			(effects
				(font
					(size 1.27 1.27)
				)
			)
		)
		(property "Value" "SCD1U16V2KX-3GP"
			(at 1.1811 -2.7051 0)
			(unlocked yes)
			(layer "F.Fab")
			(hide yes)
			(effects
				(font
					(size 1.016 1.016)
					(thickness 0.1524)
				)
			)
		)
		(property "Device Type" "C402H22"
			(at 1.1811 -4.2291 0)
			(unlocked yes)
			(layer "F.Fab")
			(hide yes)
			(effects
				(font
					(size 1.016 1.016)
					(thickness 0.1524)
				)
			)
		)
		(duplicate_pad_numbers_are_jumpers no)
		(fp_rect
			(start -0.4318 0.9525)
			(end 0.4318 -0.9525)
			(stroke
				(width 0)
				(type default)
			)
			(fill no)
			(layer "F.CrtYd")
		)
		(fp_rect
			(start -0.4318 0.9525)
			(end 0.4318 -0.9525)
			(stroke
				(width 0)
				(type default)
			)
			(fill no)
			(layer "F.Fab")
		)
		(pad "1" smd custom
			(at 0 -0.4445)
			(size 0.1524 0.1524)
			(layers "F.Cu" "F.Mask" "F.Paste")
			(net "P1V53_STBY")
			(options
				(clearance outline)
				(anchor circle)
			)
			(primitives
				(gr_poly
					(pts
						(arc
							(start 0.3048 -0.2032)
							(mid 0.275042 -0.275042)
							(end 0.2032 -0.3048)
						)
						(arc
							(start -0.2032 -0.3048)
							(mid -0.275042 -0.275042)
							(end -0.3048 -0.2032)
						)
						(arc
							(start -0.3048 0.2032)
							(mid -0.275042 0.275042)
							(end -0.2032 0.3048)
						)
						(arc
							(start 0.2032 0.3048)
							(mid 0.275042 0.275042)
							(end 0.3048 0.2032)
						)
					)
					(width 0)
					(fill yes)
				)
			)
		)
		(pad "2" smd custom
			(at 0 0.4445)
			(size 0.1524 0.1524)
			(layers "F.Cu" "F.Mask" "F.Paste")
			(net "GND")
			(options
				(clearance outline)
				(anchor circle)
			)
			(primitives
				(gr_poly
					(pts
						(arc
							(start 0.3048 -0.2032)
							(mid 0.275042 -0.275042)
							(end 0.2032 -0.3048)
						)
						(arc
							(start -0.2032 -0.3048)
							(mid -0.275042 -0.275042)
							(end -0.3048 -0.2032)
						)
						(arc
							(start -0.3048 0.2032)
							(mid -0.275042 0.275042)
							(end -0.2032 0.3048)
						)
						(arc
							(start 0.2032 0.3048)
							(mid 0.275042 0.275042)
							(end 0.3048 0.2032)
						)
					)
					(width 0)
					(fill yes)
				)
			)
		)
	)
	(footprint ""
		(layer "F.Cu")
		(at 271.477486 -3.820668)
		(property "Reference" "R216"
			(at 0 0 0)
			(layer "F.SilkS")
			(hide yes)
			(effects
				(font
					(size 1.27 1.27)
				)
			)
		)
		(property "Value" "4K7R2F-GP"
			(at 0.064008 -3.993896 0)
			(unlocked yes)
			(layer "F.Fab")
			(hide yes)
			(effects
				(font
					(size 1.016 1.016)
					(thickness 0.1524)
				)
			)
		)
		(property "Device Type" "R402H16"
			(at 0.064008 -5.517896 0)
			(unlocked yes)
			(layer "F.Fab")
			(hide yes)
			(effects
				(font
					(size 1.016 1.016)
					(thickness 0.1524)
				)
			)
		)
		(duplicate_pad_numbers_are_jumpers no)
		(fp_line
			(start -0.508 -0.9398)
			(end -0.508 0.9398)
			(stroke
				(width 0.1524)
				(type default)
			)
			(layer "F.SilkS")
		)
		(fp_line
			(start 0.508 -0.9398)
			(end -0.508 -0.9398)
			(stroke
				(width 0.1524)
				(type default)
			)
			(layer "F.SilkS")
		)
		(fp_rect
			(start -0.508 0.9398)
			(end 0.508 -0.9398)
			(stroke
				(width 0)
				(type default)
			)
			(fill no)
			(layer "F.CrtYd")
		)
		(fp_rect
			(start -0.508 0.9398)
			(end 0.508 -0.9398)
			(stroke
				(width 0)
				(type default)
			)
			(fill no)
			(layer "F.Fab")
		)
		(pad "1" smd custom
			(at 0 -0.4445)
			(size 0.1397 0.1397)
			(layers "F.Cu" "F.Mask" "F.Paste")
			(net "CLK_P_7_R")
			(options
				(clearance outline)
				(anchor circle)
			)
			(primitives
				(gr_poly
					(pts
						(arc
							(start -0.1778 -0.2794)
							(mid -0.249642 -0.249642)
							(end -0.2794 -0.1778)
						)
						(arc
							(start -0.2794 0.1778)
							(mid -0.249642 0.249642)
							(end -0.1778 0.2794)
						)
						(arc
							(start 0.1778 0.2794)
							(mid 0.249642 0.249642)
							(end 0.2794 0.1778)
						)
						(arc
							(start 0.2794 -0.1778)
							(mid 0.249642 -0.249642)
							(end 0.1778 -0.2794)
						)
					)
					(width 0)
					(fill yes)
				)
			)
		)
		(pad "2" smd custom
			(at 0 0.4445)
			(size 0.1397 0.1397)
			(layers "F.Cu" "F.Mask" "F.Paste")
			(net "GND")
			(options
				(clearance outline)
				(anchor circle)
			)
			(primitives
				(gr_poly
					(pts
						(arc
							(start -0.1778 -0.2794)
							(mid -0.249642 -0.249642)
							(end -0.2794 -0.1778)
						)
						(arc
							(start -0.2794 0.1778)
							(mid -0.249642 0.249642)
							(end -0.1778 0.2794)
						)
						(arc
							(start 0.1778 0.2794)
							(mid 0.249642 0.249642)
							(end 0.2794 0.1778)
						)
						(arc
							(start 0.2794 -0.1778)
							(mid 0.249642 -0.249642)
							(end 0.1778 -0.2794)
						)
					)
					(width 0)
					(fill yes)
				)
			)
		)
	)
	(footprint ""
		(layer "F.Cu")
		(at 44.45 -118.364)
		(property "Reference" "TP92"
			(at 0 0 0)
			(layer "F.SilkS")
			(hide yes)
			(effects
				(font
					(size 1.27 1.27)
				)
			)
		)
		(property "Value" "TPAD28-2-GP"
			(at -0.0127 -1.6637 0)
			(unlocked yes)
			(layer "F.Fab")
			(hide yes)
			(effects
				(font
					(size 1.016 1.016)
					(thickness 0.1524)
				)
			)
		)
		(property "Device Type" "TPAD28"
			(at -0.0127 -3.1877 0)
			(unlocked yes)
			(layer "F.Fab")
			(hide yes)
			(effects
				(font
					(size 1.016 1.016)
					(thickness 0.1524)
				)
			)
		)
		(duplicate_pad_numbers_are_jumpers no)
		(fp_poly
			(pts
				(arc
					(start 0.3556 0)
					(mid -0.3556 0)
					(end 0.3556 0)
				)
			)
			(stroke
				(width 0)
				(type default)
			)
			(fill no)
			(layer "F.CrtYd")
		)
		(fp_poly
			(pts
				(arc
					(start 0.6096 0)
					(mid -0.6096 0)
					(end 0.6096 0)
				)
			)
			(stroke
				(width 0)
				(type default)
			)
			(fill no)
			(layer "F.Fab")
		)
		(pad "1" smd circle
			(at 0 0)
			(size 0.7112 0.7112)
			(layers "F.Cu" "F.Mask" "F.Paste")
			(net "TP_GPIOH3")
		)
	)
	(footprint ""
		(layer "F.Cu")
		(at 205.600046 0 90)
		(property "Reference" "LED5"
			(at 0 0 90)
			(layer "F.SilkS")
			(hide yes)
			(effects
				(font
					(size 1.27 1.27)
				)
			)
		)
		(property "Value" "LED-B-77-GP-U3"
			(at -0.7112 -3.6068 90)
			(unlocked yes)
			(layer "F.Fab")
			(hide yes)
			(effects
				(font
					(size 1.016 1.016)
					(thickness 0.1524)
				)
			)
		)
		(property "Device Type" "LED3020AK-U2H44"
			(at -0.7112 -5.1308 90)
			(unlocked yes)
			(layer "F.Fab")
			(hide yes)
			(effects
				(font
					(size 1.016 1.016)
					(thickness 0.1524)
				)
			)
		)
		(duplicate_pad_numbers_are_jumpers no)
		(fp_line
			(start 0.8382 -2.4003)
			(end -0.8382 -2.4003)
			(stroke
				(width 0.1524)
				(type default)
			)
			(layer "F.SilkS")
		)
		(fp_line
			(start -0.8382 -2.4003)
			(end -0.8382 -1.31445)
			(stroke
				(width 0.1524)
				(type default)
			)
			(layer "F.SilkS")
		)
		(fp_line
			(start -0.8382 1.31445)
			(end -0.8382 2.4003)
			(stroke
				(width 0.1524)
				(type default)
			)
			(layer "F.SilkS")
		)
		(fp_line
			(start 0.8382 2.4003)
			(end 0.8382 -2.4003)
			(stroke
				(width 0.1524)
				(type default)
			)
			(layer "F.SilkS")
		)
		(fp_line
			(start -0.8382 2.4003)
			(end 0.8382 2.4003)
			(stroke
				(width 0.1524)
				(type default)
			)
			(layer "F.SilkS")
		)
		(fp_line
			(start 0.889 2.5273)
			(end -0.889 2.5273)
			(stroke
				(width 0.4064)
				(type default)
			)
			(layer "F.SilkS")
		)
		(fp_arc
			(start -0.8382 1.31445)
			(mid -1.85412 0)
			(end -0.8382 -1.31445)
			(stroke
				(width 0.1524)
				(type default)
			)
			(layer "F.SilkS")
		)
		(fp_poly
			(pts
				(xy -1.0922 2.6543) (xy -1.0922 1.49606) (xy -1.15189 1.4732) (xy -1.27254 1.41351) (xy -1.38557 1.34493)
				(xy -1.49098 1.26873) (xy -1.59258 1.18237) (xy -1.68656 1.08712) (xy -1.77165 0.98552) (xy -1.84785 0.87757)
				(xy -1.91516 0.76454) (xy -1.97358 0.64262) (xy -2.02057 0.5207) (xy -2.05867 0.3937) (xy -2.08534 0.26416)
				(xy -2.10185 0.13335) (xy -2.1082 0) (xy -2.10185 -0.13335) (xy -2.08534 -0.26416) (xy -2.05867 -0.3937)
				(xy -2.02057 -0.5207) (xy -1.97358 -0.64262) (xy -1.91516 -0.76454) (xy -1.84785 -0.87757) (xy -1.77165 -0.98552)
				(xy -1.68656 -1.08712) (xy -1.59258 -1.18237) (xy -1.49098 -1.26873) (xy -1.38557 -1.34493) (xy -1.27254 -1.41351)
				(xy -1.15189 -1.4732) (xy -1.0922 -1.49606) (xy -1.0922 -2.6543) (xy 1.0922 -2.6543) (xy 1.0922 2.6543)
			)
			(stroke
				(width 0)
				(type default)
			)
			(fill no)
			(layer "F.CrtYd")
		)
		(fp_poly
			(pts
				(xy -1.0922 2.6543) (xy -1.0922 1.49606) (xy -1.15189 1.4732) (xy -1.27254 1.41351) (xy -1.38557 1.34493)
				(xy -1.49098 1.26873) (xy -1.59258 1.18237) (xy -1.68656 1.08712) (xy -1.77165 0.98552) (xy -1.84785 0.87757)
				(xy -1.91516 0.76454) (xy -1.97358 0.64262) (xy -2.02057 0.5207) (xy -2.05867 0.3937) (xy -2.08534 0.26416)
				(xy -2.10185 0.13335) (xy -2.1082 0) (xy -2.10185 -0.13335) (xy -2.08534 -0.26416) (xy -2.05867 -0.3937)
				(xy -2.02057 -0.5207) (xy -1.97358 -0.64262) (xy -1.91516 -0.76454) (xy -1.84785 -0.87757) (xy -1.77165 -0.98552)
				(xy -1.68656 -1.08712) (xy -1.59258 -1.18237) (xy -1.49098 -1.26873) (xy -1.38557 -1.34493) (xy -1.27254 -1.41351)
				(xy -1.15189 -1.4732) (xy -1.0922 -1.49606) (xy -1.0922 -2.6543) (xy 1.0922 -2.6543) (xy 1.0922 2.6543)
			)
			(stroke
				(width 0)
				(type default)
			)
			(fill no)
			(layer "F.Fab")
		)
		(pad "A" smd rect
			(at 0 -1.57099 90)
			(size 1.143 1.143)
			(layers "F.Cu" "F.Mask" "F.Paste")
			(net "LED_PWR_N_R")
		)
		(pad "K" smd rect
			(at 0 1.57099 90)
			(size 1.143 1.143)
			(layers "F.Cu" "F.Mask" "F.Paste")
			(net "LED_PWR_N_ON")
		)
	)
	(footprint ""
		(layer "F.Cu")
		(at 260.096 -26.289 180)
		(property "Reference" "R747"
			(at 0 0 180)
			(layer "F.SilkS")
			(hide yes)
			(effects
				(font
					(size 1.27 1.27)
				)
			)
		)
		(property "Value" "4K7R2F-GP"
			(at 0.064008 -3.993896 180)
			(unlocked yes)
			(layer "F.Fab")
			(hide yes)
			(effects
				(font
					(size 1.016 1.016)
					(thickness 0.1524)
				)
			)
		)
		(property "Device Type" "R402H16"
			(at 0.064008 -5.517896 180)
			(unlocked yes)
			(layer "F.Fab")
			(hide yes)
			(effects
				(font
					(size 1.016 1.016)
					(thickness 0.1524)
				)
			)
		)
		(duplicate_pad_numbers_are_jumpers no)
		(fp_line
			(start 0.508 -0.9398)
			(end -0.508 -0.9398)
			(stroke
				(width 0.1524)
				(type default)
			)
			(layer "F.SilkS")
		)
		(fp_line
			(start -0.508 -0.9398)
			(end -0.508 0.9398)
			(stroke
				(width 0.1524)
				(type default)
			)
			(layer "F.SilkS")
		)
		(fp_rect
			(start -0.508 0.9398)
			(end 0.508 -0.9398)
			(stroke
				(width 0)
				(type default)
			)
			(fill no)
			(layer "F.CrtYd")
		)
		(fp_rect
			(start -0.508 0.9398)
			(end 0.508 -0.9398)
			(stroke
				(width 0)
				(type default)
			)
			(fill no)
			(layer "F.Fab")
		)
		(pad "1" smd custom
			(at 0 -0.4445 180)
			(size 0.1397 0.1397)
			(layers "F.Cu" "F.Mask" "F.Paste")
			(net "P3V3_GPIO")
			(options
				(clearance outline)
				(anchor circle)
			)
			(primitives
				(gr_poly
					(pts
						(arc
							(start -0.1778 -0.2794)
							(mid -0.249642 -0.249642)
							(end -0.2794 -0.1778)
						)
						(arc
							(start -0.2794 0.1778)
							(mid -0.249642 0.249642)
							(end -0.1778 0.2794)
						)
						(arc
							(start 0.1778 0.2794)
							(mid 0.249642 0.249642)
							(end 0.2794 0.1778)
						)
						(arc
							(start 0.2794 -0.1778)
							(mid 0.249642 -0.249642)
							(end 0.1778 -0.2794)
						)
					)
					(width 0)
					(fill yes)
				)
			)
		)
		(pad "2" smd custom
			(at 0 0.4445 180)
			(size 0.1397 0.1397)
			(layers "F.Cu" "F.Mask" "F.Paste")
			(net "IOEXP_PMC1_INT#")
			(options
				(clearance outline)
				(anchor circle)
			)
			(primitives
				(gr_poly
					(pts
						(arc
							(start -0.1778 -0.2794)
							(mid -0.249642 -0.249642)
							(end -0.2794 -0.1778)
						)
						(arc
							(start -0.2794 0.1778)
							(mid -0.249642 0.249642)
							(end -0.1778 0.2794)
						)
						(arc
							(start 0.1778 0.2794)
							(mid 0.249642 0.249642)
							(end 0.2794 0.1778)
						)
						(arc
							(start 0.2794 -0.1778)
							(mid 0.249642 -0.249642)
							(end 0.1778 -0.2794)
						)
					)
					(width 0)
					(fill yes)
				)
			)
		)
	)
)
